(kicad_pcb
	(version 20260206)
	(generator "pcbnew")
	(generator_version "10.0")
	(general
		(thickness 1.6)
		(legacy_teardrops no)
	)
	(paper "A4")
	(title_block
		(title "12092022_DA0F0TMDCD0_F0T_Management_Board_D_brd_V3_OCP.brd")
		(comment 1 "Grand Teton / footprints 1275-1278 of 1440")
	)
	(layers
		(0 "F.Cu" signal "TOP")
		(4 "In1.Cu" signal "GND")
		(6 "In2.Cu" signal "IN1")
		(8 "In3.Cu" signal "GND1")
		(10 "In4.Cu" signal "IN2")
		(12 "In5.Cu" signal "VCC")
		(14 "In6.Cu" signal "VCC1")
		(16 "In7.Cu" signal "IN3")
		(18 "In8.Cu" signal "GND2")
		(20 "In9.Cu" signal "IN4")
		(22 "In10.Cu" signal "GND3")
		(2 "B.Cu" signal "BOTTOM")
		(9 "F.Adhes" user "F.Adhesive")
		(11 "B.Adhes" user "B.Adhesive")
		(13 "F.Paste" user "Package Geometry/Pastemask Top")
		(15 "B.Paste" user "Package Geometry/Pastemask Bottom")
		(5 "F.SilkS" user "Ref Des/Silkscreen Top")
		(7 "B.SilkS" user "Ref Des/Silkscreen Bottom")
		(1 "F.Mask" user "Board Geometry/Soldermask Top")
		(3 "B.Mask" user "Board Geometry/Soldermask Bottom")
		(17 "Dwgs.User" user "User.Drawings")
		(19 "Cmts.User" user "User.Comments")
		(21 "Eco1.User" user "User.Eco1")
		(23 "Eco2.User" user "User.Eco2")
		(25 "Edge.Cuts" user "Board Geometry/Outline")
		(27 "Margin" user)
		(31 "F.CrtYd" user "Package Geometry/Place Bound Top")
		(29 "B.CrtYd" user "Package Geometry/Place Bound Bottom")
		(35 "F.Fab" user "Ref Des/Assembly Top")
		(33 "B.Fab" user "Ref Des/Assembly Bottom")
	)
	(footprint ""
		(layer "B.Cu")
		(at 32.96793 -38.8747 90)
		(property "Reference" "R27"
			(at 0 0 90)
			(layer "B.SilkS")
			(hide yes)
			(effects
				(font
					(size 1.27 1.27)
				)
				(justify mirror)
			)
		)
		(property "Value" ""
			(at 0 0 90)
			(layer "B.Fab")
			(effects
				(font
					(size 1.27 1.27)
				)
				(justify mirror)
			)
		)
		(duplicate_pad_numbers_are_jumpers no)
		(fp_line
			(start 1.2954 -0.5842)
			(end -1.2954 -0.5842)
			(stroke
				(width 0.1524)
				(type default)
			)
			(layer "B.SilkS")
		)
		(fp_line
			(start -1.2954 -0.5842)
			(end -1.2954 0.5842)
			(stroke
				(width 0.1524)
				(type default)
			)
			(layer "B.SilkS")
		)
		(fp_line
			(start 1.2954 0.5842)
			(end 1.2954 -0.5842)
			(stroke
				(width 0.1524)
				(type default)
			)
			(layer "B.SilkS")
		)
		(fp_line
			(start -1.2954 0.5842)
			(end 1.2954 0.5842)
			(stroke
				(width 0.1524)
				(type default)
			)
			(layer "B.SilkS")
		)
		(fp_line
			(start 0.8636 -0.4572)
			(end -0.8636 -0.4572)
			(stroke
				(width 0.1)
				(type default)
			)
			(layer "B.Fab")
		)
		(fp_line
			(start -0.8636 -0.4572)
			(end -0.8636 -0.406654)
			(stroke
				(width 0.1)
				(type default)
			)
			(layer "B.Fab")
		)
		(fp_line
			(start 1.1938 -0.406654)
			(end 0.8636 -0.406654)
			(stroke
				(width 0.1)
				(type default)
			)
			(layer "B.Fab")
		)
		(fp_line
			(start 0.8636 -0.406654)
			(end 0.8636 -0.4572)
			(stroke
				(width 0.1)
				(type default)
			)
			(layer "B.Fab")
		)
		(fp_line
			(start -0.8636 -0.406654)
			(end -1.1938 -0.406654)
			(stroke
				(width 0.1)
				(type default)
			)
			(layer "B.Fab")
		)
		(fp_line
			(start -1.1938 -0.406654)
			(end -1.1938 0.4064)
			(stroke
				(width 0.1)
				(type default)
			)
			(layer "B.Fab")
		)
		(fp_line
			(start 1.1938 0.4064)
			(end 1.1938 -0.406654)
			(stroke
				(width 0.1)
				(type default)
			)
			(layer "B.Fab")
		)
		(fp_line
			(start 0.8636 0.4064)
			(end 1.1938 0.4064)
			(stroke
				(width 0.1)
				(type default)
			)
			(layer "B.Fab")
		)
		(fp_line
			(start -0.8636 0.4064)
			(end -0.8636 0.4572)
			(stroke
				(width 0.1)
				(type default)
			)
			(layer "B.Fab")
		)
		(fp_line
			(start -1.1938 0.4064)
			(end -0.8636 0.4064)
			(stroke
				(width 0.1)
				(type default)
			)
			(layer "B.Fab")
		)
		(fp_line
			(start 0.8636 0.4318)
			(end 0.8636 0.4064)
			(stroke
				(width 0.1)
				(type default)
			)
			(layer "B.Fab")
		)
		(fp_line
			(start 0.8636 0.4572)
			(end 0.8636 0.4318)
			(stroke
				(width 0.1)
				(type default)
			)
			(layer "B.Fab")
		)
		(fp_line
			(start -0.8636 0.4572)
			(end 0.8636 0.4572)
			(stroke
				(width 0.1)
				(type default)
			)
			(layer "B.Fab")
		)
		(pad "1" smd rect
			(at 0.7366 0)
			(size 0.7112 0.8128)
			(layers "B.Cu" "B.Mask" "B.Paste")
			(net "P5V_AUX")
		)
		(pad "2" smd rect
			(at -0.7366 0)
			(size 0.7112 0.8128)
			(layers "B.Cu" "B.Mask" "B.Paste")
			(net "CRT_VCC5")
		)
	)
	(footprint ""
		(layer "B.Cu")
		(at 112.014 54.61 90)
		(property "Reference" "X14"
			(at 1.73863 3.2385 0)
			(unlocked yes)
			(layer "B.SilkS")
			(effects
				(font
					(size 0.7874 0.5842)
					(thickness 0.1524)
				)
				(justify left mirror)
			)
		)
		(property "Value" ""
			(at 0 0 90)
			(layer "B.Fab")
			(effects
				(font
					(size 1.27 1.27)
				)
				(justify mirror)
			)
		)
		(property "Device Type" "TP_TDR_4P_FTS_TH-TP_TDR_4P_DIPA"
			(at -1.30175 1.27 0)
			(unlocked yes)
			(layer "B.Fab")
			(hide yes)
			(effects
				(font
					(size 0.635 0.4064)
					(thickness 0.1524)
				)
				(justify mirror)
			)
		)
		(property "User Part Number" "N_A"
			(at -1.30175 1.27 0)
			(unlocked yes)
			(layer "Cmts.User")
			(hide yes)
			(effects
				(font
					(size 0.635 0.4064)
					(thickness 0.1524)
				)
				(justify mirror)
			)
		)
		(duplicate_pad_numbers_are_jumpers no)
		(fp_line
			(start 0 -1.27)
			(end 0 -0.635)
			(stroke
				(width 0.1524)
				(type default)
			)
			(layer "B.SilkS")
		)
		(fp_line
			(start -2.54 -1.27)
			(end 0 -1.27)
			(stroke
				(width 0.1524)
				(type default)
			)
			(layer "B.SilkS")
		)
		(fp_line
			(start -2.54 -1.1303)
			(end -2.54 -1.27)
			(stroke
				(width 0.1524)
				(type default)
			)
			(layer "B.SilkS")
		)
		(fp_line
			(start 0 0.635)
			(end 0 1.905)
			(stroke
				(width 0.1524)
				(type default)
			)
			(layer "B.SilkS")
		)
		(fp_line
			(start -2.54 1.4097)
			(end -2.54 1.1303)
			(stroke
				(width 0.1524)
				(type default)
			)
			(layer "B.SilkS")
		)
		(fp_line
			(start 0 3.175)
			(end 0 3.81)
			(stroke
				(width 0.1524)
				(type default)
			)
			(layer "B.SilkS")
		)
		(fp_line
			(start 0 3.81)
			(end -2.54 3.81)
			(stroke
				(width 0.1524)
				(type default)
			)
			(layer "B.SilkS")
		)
		(fp_line
			(start -2.54 3.81)
			(end -2.54 3.6703)
			(stroke
				(width 0.1524)
				(type default)
			)
			(layer "B.SilkS")
		)
		(fp_poly
			(pts
				(xy 0.761746 0) (xy 2.285746 -0.762) (xy 2.285746 0.762)
			)
			(stroke
				(width 0)
				(type default)
			)
			(fill yes)
			(layer "B.SilkS")
		)
		(fp_line
			(start 0 -1.27)
			(end 0 3.81)
			(stroke
				(width 0.1)
				(type default)
			)
			(layer "B.Fab")
		)
		(fp_line
			(start -2.54 -1.27)
			(end 0 -1.27)
			(stroke
				(width 0.1)
				(type default)
			)
			(layer "B.Fab")
		)
		(fp_line
			(start 0 3.81)
			(end -2.54 3.81)
			(stroke
				(width 0.1)
				(type default)
			)
			(layer "B.Fab")
		)
		(fp_line
			(start -2.54 3.81)
			(end -2.54 -1.27)
			(stroke
				(width 0.1)
				(type default)
			)
			(layer "B.Fab")
		)
		(fp_poly
			(pts
				(xy 0.761746 0) (xy 2.285746 -0.762) (xy 2.285746 0.762)
			)
			(stroke
				(width 0)
				(type default)
			)
			(fill yes)
			(layer "B.Fab")
		)
		(pad "1" thru_hole circle
			(at 0 0 270)
			(size 1.0033 1.0033)
			(drill 0.249936)
			(layers "*.Cu" "*.Mask")
			(remove_unused_layers no)
			(net "TDR_DIFF_100_IN1_DP")
			(clearance 0.10795)
			(padstack
				(mode front_inner_back)
				(layer "Inner"
					(shape circle)
					(size 0.8001 0.8001)
					(clearance 0.1524)
				)
				(layer "B.Cu"
					(shape circle)
					(size 1.0033 1.0033)
					(thermal_gap 0.10795)
					(clearance 0.10795)
				)
			)
		)
		(pad "2" thru_hole circle
			(at -2.54 0 270)
			(size 1.9939 1.9939)
			(drill 0.249936)
			(layers "*.Cu" "*.Mask")
			(remove_unused_layers no)
			(net "GND_P1")
			(clearance 0.10795)
			(padstack
				(mode front_inner_back)
				(layer "Inner"
					(shape circle)
					(size 0.8001 0.8001)
					(clearance 0.1524)
				)
				(layer "B.Cu"
					(shape circle)
					(size 1.9939 1.9939)
					(thermal_gap 0.10795)
					(clearance 0.10795)
				)
			)
		)
		(pad "3" thru_hole circle
			(at -2.54 2.54 270)
			(size 1.9939 1.9939)
			(drill 0.249936)
			(layers "*.Cu" "*.Mask")
			(remove_unused_layers no)
			(net "GND_P1")
			(clearance 0.10795)
			(padstack
				(mode front_inner_back)
				(layer "Inner"
					(shape circle)
					(size 0.8001 0.8001)
					(clearance 0.1524)
				)
				(layer "B.Cu"
					(shape circle)
					(size 1.9939 1.9939)
					(thermal_gap 0.10795)
					(clearance 0.10795)
				)
			)
		)
		(pad "4" thru_hole circle
			(at 0 2.54 270)
			(size 1.0033 1.0033)
			(drill 0.249936)
			(layers "*.Cu" "*.Mask")
			(remove_unused_layers no)
			(net "TDR_DIFF_100_IN1_DN")
			(clearance 0.10795)
			(padstack
				(mode front_inner_back)
				(layer "Inner"
					(shape circle)
					(size 0.8001 0.8001)
					(clearance 0.1524)
				)
				(layer "B.Cu"
					(shape circle)
					(size 1.0033 1.0033)
					(thermal_gap 0.10795)
					(clearance 0.10795)
				)
			)
		)
	)
	(footprint ""
		(layer "B.Cu")
		(at 17.2974 -83.693 90)
		(property "Reference" "R397"
			(at 0 0 90)
			(layer "B.SilkS")
			(hide yes)
			(effects
				(font
					(size 1.27 1.27)
				)
				(justify mirror)
			)
		)
		(property "Value" ""
			(at 0 0 90)
			(layer "B.Fab")
			(effects
				(font
					(size 1.27 1.27)
				)
				(justify mirror)
			)
		)
		(duplicate_pad_numbers_are_jumpers no)
		(fp_line
			(start 0.7874 -0.4064)
			(end -0.7874 -0.4064)
			(stroke
				(width 0.1524)
				(type default)
			)
			(layer "B.SilkS")
		)
		(fp_line
			(start -0.7874 -0.4064)
			(end -0.7874 0.4064)
			(stroke
				(width 0.1524)
				(type default)
			)
			(layer "B.SilkS")
		)
		(fp_line
			(start 0.7874 0.4064)
			(end 0.7874 -0.4064)
			(stroke
				(width 0.1524)
				(type default)
			)
			(layer "B.SilkS")
		)
		(fp_line
			(start -0.7874 0.4064)
			(end 0.7874 0.4064)
			(stroke
				(width 0.1524)
				(type default)
			)
			(layer "B.SilkS")
		)
		(fp_line
			(start 0.67945 -0.305054)
			(end 0.12065 -0.305054)
			(stroke
				(width 0.1)
				(type default)
			)
			(layer "B.Fab")
		)
		(fp_line
			(start 0.12065 -0.305054)
			(end 0.12065 -0.2794)
			(stroke
				(width 0.1)
				(type default)
			)
			(layer "B.Fab")
		)
		(fp_line
			(start -0.12065 -0.3048)
			(end -0.67945 -0.3048)
			(stroke
				(width 0.1)
				(type default)
			)
			(layer "B.Fab")
		)
		(fp_line
			(start -0.67945 -0.3048)
			(end -0.67945 0.3048)
			(stroke
				(width 0.1)
				(type default)
			)
			(layer "B.Fab")
		)
		(fp_line
			(start 0.12065 -0.2794)
			(end -0.12065 -0.2794)
			(stroke
				(width 0.1)
				(type default)
			)
			(layer "B.Fab")
		)
		(fp_line
			(start -0.12065 -0.2794)
			(end -0.12065 -0.3048)
			(stroke
				(width 0.1)
				(type default)
			)
			(layer "B.Fab")
		)
		(fp_line
			(start 0.12065 0.2794)
			(end 0.12065 0.3048)
			(stroke
				(width 0.1)
				(type default)
			)
			(layer "B.Fab")
		)
		(fp_line
			(start -0.120396 0.2794)
			(end 0.12065 0.2794)
			(stroke
				(width 0.1)
				(type default)
			)
			(layer "B.Fab")
		)
		(fp_line
			(start 0.67945 0.3048)
			(end 0.67945 -0.305054)
			(stroke
				(width 0.1)
				(type default)
			)
			(layer "B.Fab")
		)
		(fp_line
			(start 0.12065 0.3048)
			(end 0.67945 0.3048)
			(stroke
				(width 0.1)
				(type default)
			)
			(layer "B.Fab")
		)
		(fp_line
			(start -0.120396 0.3048)
			(end -0.120396 0.2794)
			(stroke
				(width 0.1)
				(type default)
			)
			(layer "B.Fab")
		)
		(fp_line
			(start -0.67945 0.3048)
			(end -0.120396 0.3048)
			(stroke
				(width 0.1)
				(type default)
			)
			(layer "B.Fab")
		)
		(pad "1" smd circle
			(at 0.40005 0 270)
			(size 0 0)
			(layers "B.Cu" "B.Mask" "B.Paste")
			(net "JTAG_SCM_PLD_R_JTAGEN")
		)
		(pad "2" smd circle
			(at -0.40005 0 270)
			(size 0 0)
			(layers "B.Cu" "B.Mask" "B.Paste")
			(net "JTAG_SCM_PLD_JTAGEN")
		)
	)
	(footprint ""
		(layer "B.Cu")
		(at 57.63768 -89.72042)
		(property "Reference" "U40"
			(at 0.97282 4.66979 0)
			(unlocked yes)
			(layer "B.SilkS")
			(effects
				(font
					(size 0.7874 0.5842)
					(thickness 0.1524)
				)
				(justify left mirror)
			)
		)
		(property "Value" ""
			(at 0 0 0)
			(layer "B.Fab")
			(effects
				(font
					(size 1.27 1.27)
				)
				(justify mirror)
			)
		)
		(duplicate_pad_numbers_are_jumpers no)
		(fp_line
			(start -2.0066 -3.9624)
			(end -2.0066 3.9624)
			(stroke
				(width 0.1524)
				(type default)
			)
			(layer "B.SilkS")
		)
		(fp_line
			(start -2.0066 3.9624)
			(end 2.0066 3.9624)
			(stroke
				(width 0.1524)
				(type default)
			)
			(layer "B.SilkS")
		)
		(fp_line
			(start -0.5842 -3.9624)
			(end -2.0066 -3.9624)
			(stroke
				(width 0.1524)
				(type default)
			)
			(layer "B.SilkS")
		)
		(fp_line
			(start 0 -3.3782)
			(end -0.5842 -3.9624)
			(stroke
				(width 0.1524)
				(type default)
			)
			(layer "B.SilkS")
		)
		(fp_line
			(start 0.5842 -3.9624)
			(end 0 -3.3782)
			(stroke
				(width 0.1524)
				(type default)
			)
			(layer "B.SilkS")
		)
		(fp_line
			(start 2.0066 -3.9624)
			(end 0.5842 -3.9624)
			(stroke
				(width 0.1524)
				(type default)
			)
			(layer "B.SilkS")
		)
		(fp_line
			(start 2.0066 3.9624)
			(end 2.0066 -3.9624)
			(stroke
				(width 0.1524)
				(type default)
			)
			(layer "B.SilkS")
		)
		(fp_poly
			(pts
				(xy 3.502914 -3.90906) (xy 3.883914 -4.67106) (xy 3.121914 -4.67106)
			)
			(stroke
				(width 0)
				(type default)
			)
			(fill yes)
			(layer "B.SilkS")
		)
		(fp_line
			(start -3.7211 -3.80365)
			(end -2.2479 -3.80365)
			(stroke
				(width 0.1)
				(type default)
			)
			(layer "B.Fab")
		)
		(fp_line
			(start -3.7211 3.80365)
			(end -3.7211 -3.80365)
			(stroke
				(width 0.1)
				(type default)
			)
			(layer "B.Fab")
		)
		(fp_line
			(start -2.2479 -3.974846)
			(end 2.2479 -3.974846)
			(stroke
				(width 0.1)
				(type default)
			)
			(layer "B.Fab")
		)
		(fp_line
			(start -2.2479 -3.80365)
			(end -2.2479 -3.974846)
			(stroke
				(width 0.1)
				(type default)
			)
			(layer "B.Fab")
		)
		(fp_line
			(start -2.2479 3.80365)
			(end -3.7211 3.80365)
			(stroke
				(width 0.1)
				(type default)
			)
			(layer "B.Fab")
		)
		(fp_line
			(start -2.2479 3.9624)
			(end -2.2479 3.80365)
			(stroke
				(width 0.1)
				(type default)
			)
			(layer "B.Fab")
		)
		(fp_line
			(start 2.2479 -3.974846)
			(end 2.2479 -3.80365)
			(stroke
				(width 0.1)
				(type default)
			)
			(layer "B.Fab")
		)
		(fp_line
			(start 2.2479 -3.80365)
			(end 3.724402 -3.80365)
			(stroke
				(width 0.1)
				(type default)
			)
			(layer "B.Fab")
		)
		(fp_line
			(start 2.2479 3.80365)
			(end 2.2479 3.9624)
			(stroke
				(width 0.1)
				(type default)
			)
			(layer "B.Fab")
		)
		(fp_line
			(start 2.2479 3.9624)
			(end -2.2479 3.9624)
			(stroke
				(width 0.1)
				(type default)
			)
			(layer "B.Fab")
		)
		(fp_line
			(start 3.7211 -3.34645)
			(end 3.7211 -3.80365)
			(stroke
				(width 0.1)
				(type default)
			)
			(layer "B.Fab")
		)
		(fp_line
			(start 3.724402 -3.80365)
			(end 3.724402 3.80365)
			(stroke
				(width 0.1)
				(type default)
			)
			(layer "B.Fab")
		)
		(fp_line
			(start 3.724402 3.80365)
			(end 2.2479 3.80365)
			(stroke
				(width 0.1)
				(type default)
			)
			(layer "B.Fab")
		)
		(fp_poly
			(pts
				(xy 3.8862 -3.570986) (xy 4.6482 -3.189986) (xy 4.6482 -3.951986)
			)
			(stroke
				(width 0)
				(type default)
			)
			(fill yes)
			(layer "B.Fab")
		)
		(pad "1" smd rect
			(at 2.921 -3.57505 270)
			(size 0.3556 1.4986)
			(layers "B.Cu" "B.Mask" "B.Paste")
			(net "LED_POSTCODE_INT")
		)
		(pad "2" smd rect
			(at 2.921 -2.925064 270)
			(size 0.3556 1.4986)
			(layers "B.Cu" "B.Mask" "B.Paste")
			(net "LED_POSTCODE_A1")
		)
		(pad "3" smd rect
			(at 2.921 -2.275078 270)
			(size 0.3556 1.4986)
			(layers "B.Cu" "B.Mask" "B.Paste")
			(net "LED_POSTCODE_A2")
		)
		(pad "4" smd rect
			(at 2.921 -1.625092 270)
			(size 0.3556 1.4986)
			(layers "B.Cu" "B.Mask" "B.Paste")
			(net "LED_POSTCODE_0_R1")
		)
		(pad "5" smd rect
			(at 2.921 -0.975106 270)
			(size 0.3556 1.4986)
			(layers "B.Cu" "B.Mask" "B.Paste")
			(net "LED_POSTCODE_1_R1")
		)
		(pad "6" smd rect
			(at 2.921 -0.32512 270)
			(size 0.3556 1.4986)
			(layers "B.Cu" "B.Mask" "B.Paste")
			(net "LED_POSTCODE_2_R1")
		)
		(pad "7" smd rect
			(at 2.921 0.32512 270)
			(size 0.3556 1.4986)
			(layers "B.Cu" "B.Mask" "B.Paste")
			(net "LED_POSTCODE_3_R1")
		)
		(pad "8" smd rect
			(at 2.921 0.975106 270)
			(size 0.3556 1.4986)
			(layers "B.Cu" "B.Mask" "B.Paste")
			(net "LED_POSTCODE_4_R1")
		)
		(pad "9" smd rect
			(at 2.921 1.625092 270)
			(size 0.3556 1.4986)
			(layers "B.Cu" "B.Mask" "B.Paste")
			(net "LED_POSTCODE_5_R1")
		)
		(pad "10" smd rect
			(at 2.921 2.275078 270)
			(size 0.3556 1.4986)
			(layers "B.Cu" "B.Mask" "B.Paste")
			(net "LED_POSTCODE_6_R1")
		)
		(pad "11" smd rect
			(at 2.921 2.925064 270)
			(size 0.3556 1.4986)
			(layers "B.Cu" "B.Mask" "B.Paste")
			(net "LED_POSTCODE_7_R1")
		)
		(pad "12" smd rect
			(at 2.921 3.57505 270)
			(size 0.3556 1.4986)
			(layers "B.Cu" "B.Mask" "B.Paste")
			(net "GND")
		)
		(pad "13" smd rect
			(at -2.921 3.57505 270)
			(size 0.3556 1.4986)
			(layers "B.Cu" "B.Mask" "B.Paste")
			(net "FM_DEBUG_RST_BTN_N")
		)
		(pad "14" smd rect
			(at -2.921 2.925064 270)
			(size 0.3556 1.4986)
			(layers "B.Cu" "B.Mask" "B.Paste")
			(net "FM_DEBUG_PWR_BTN_N")
		)
		(pad "15" smd rect
			(at -2.921 2.275078 270)
			(size 0.3556 1.4986)
			(layers "B.Cu" "B.Mask" "B.Paste")
			(net "PWRGD_SYS_PWROK_R1")
		)
		(pad "16" smd rect
			(at -2.921 1.625092 270)
			(size 0.3556 1.4986)
			(layers "B.Cu" "B.Mask" "B.Paste")
			(net "RST_PLTRST_R2_N")
		)
		(pad "17" smd rect
			(at -2.921 0.975106 270)
			(size 0.3556 1.4986)
			(layers "B.Cu" "B.Mask" "B.Paste")
			(net "PWRGD_DSW_PWROK_R3")
		)
		(pad "18" smd rect
			(at -2.921 0.32512 270)
			(size 0.3556 1.4986)
			(layers "B.Cu" "B.Mask" "B.Paste")
			(net "FM_CPU_MSMI_CATERR_LVT3_R3_N")
		)
		(pad "19" smd rect
			(at -2.921 -0.32512 270)
			(size 0.3556 1.4986)
			(layers "B.Cu" "B.Mask" "B.Paste")
			(net "FM_SLPS3_GF_R2_N")
		)
		(pad "20" smd rect
			(at -2.921 -0.975106 270)
			(size 0.3556 1.4986)
			(layers "B.Cu" "B.Mask" "B.Paste")
			(net "FM_UART_SWITCH_N")
		)
		(pad "21" smd rect
			(at -2.921 -1.625092 270)
			(size 0.3556 1.4986)
			(layers "B.Cu" "B.Mask" "B.Paste")
			(net "LED_POSTCODE_A0")
		)
		(pad "22" smd rect
			(at -2.921 -2.275078 270)
			(size 0.3556 1.4986)
			(layers "B.Cu" "B.Mask" "B.Paste")
			(net "SMB_DEBUG_AUX_LVC3_USB_R3_SCL")
		)
		(pad "23" smd rect
			(at -2.921 -2.925064 270)
			(size 0.3556 1.4986)
			(layers "B.Cu" "B.Mask" "B.Paste")
			(net "SMB_DEBUG_AUX_LVC3_USB_R3_SDA")
		)
		(pad "24" smd rect
			(at -2.921 -3.57505 270)
			(size 0.3556 1.4986)
			(layers "B.Cu" "B.Mask" "B.Paste")
			(net "P3V3_AUX")
		)
	)
)
